(kicad_pcb
	(version 20260206)
	(generator "pcbnew")
	(generator_version "10.0")
	(general
		(thickness 1.6)
		(legacy_teardrops no)
	)
	(paper "A4")
	(title_block
		(title "04192023_DAF0TMB3IC0_F0TG_MB_C_brd_V02_OCP.brd")
		(comment 1 "Grand Teton / footprints 7987-7995 of 8354")
	)
	(layers
		(0 "F.Cu" signal "TOP")
		(4 "In1.Cu" signal "GND")
		(6 "In2.Cu" signal "IN1")
		(8 "In3.Cu" signal "GND1")
		(10 "In4.Cu" signal "IN2")
		(12 "In5.Cu" signal "GND2")
		(14 "In6.Cu" signal "IN3")
		(16 "In7.Cu" signal "GND3")
		(18 "In8.Cu" signal "VCC")
		(20 "In9.Cu" signal "VCC1")
		(22 "In10.Cu" signal "GND4")
		(24 "In11.Cu" signal "IN4")
		(26 "In12.Cu" signal "GND5")
		(28 "In13.Cu" signal "IN5")
		(30 "In14.Cu" signal "GND6")
		(32 "In15.Cu" signal "IN6")
		(34 "In16.Cu" signal "GND7")
		(2 "B.Cu" signal "BOTTOM")
		(9 "F.Adhes" user "F.Adhesive")
		(11 "B.Adhes" user "B.Adhesive")
		(13 "F.Paste" user "Package Geometry/Pastemask Top")
		(15 "B.Paste" user "Package Geometry/Pastemask Bottom")
		(5 "F.SilkS" user "Ref Des/Silkscreen Top")
		(7 "B.SilkS" user "Ref Des/Silkscreen Bottom")
		(1 "F.Mask" user "Board Geometry/Soldermask Top")
		(3 "B.Mask" user "Board Geometry/Soldermask Bottom")
		(17 "Dwgs.User" user "User.Drawings")
		(19 "Cmts.User" user "User.Comments")
		(21 "Eco1.User" user "User.Eco1")
		(23 "Eco2.User" user "User.Eco2")
		(25 "Edge.Cuts" user "Board Geometry/Outline")
		(27 "Margin" user)
		(31 "F.CrtYd" user "Package Geometry/Place Bound Top")
		(29 "B.CrtYd" user "Package Geometry/Place Bound Bottom")
		(35 "F.Fab" user "Ref Des/Assembly Top")
		(33 "B.Fab" user "Ref Des/Assembly Bottom")
	)
	(footprint ""
		(layer "B.Cu")
		(at 228.834442 -315.95568 -90)
		(property "Reference" "PC6527"
			(at 0 0 90)
			(layer "B.SilkS")
			(hide yes)
			(effects
				(font
					(size 1.27 1.27)
				)
				(justify mirror)
			)
		)
		(property "Value" ""
			(at 0 0 90)
			(layer "B.Fab")
			(effects
				(font
					(size 1.27 1.27)
				)
				(justify mirror)
			)
		)
		(duplicate_pad_numbers_are_jumpers no)
		(fp_line
			(start -1.524 0.762)
			(end 1.524 0.762)
			(stroke
				(width 0.1524)
				(type default)
			)
			(layer "B.SilkS")
		)
		(fp_line
			(start 1.524 0.762)
			(end 1.524 -0.762)
			(stroke
				(width 0.1524)
				(type default)
			)
			(layer "B.SilkS")
		)
		(fp_line
			(start -1.524 -0.762)
			(end -1.524 0.762)
			(stroke
				(width 0.1524)
				(type default)
			)
			(layer "B.SilkS")
		)
		(fp_line
			(start 1.524 -0.762)
			(end -1.524 -0.762)
			(stroke
				(width 0.1524)
				(type default)
			)
			(layer "B.SilkS")
		)
		(fp_line
			(start -1.1049 0.724916)
			(end -1.1049 -0.724916)
			(stroke
				(width 0.1)
				(type default)
			)
			(layer "B.Fab")
		)
		(fp_line
			(start 1.1049 0.724916)
			(end -1.1049 0.724916)
			(stroke
				(width 0.1)
				(type default)
			)
			(layer "B.Fab")
		)
		(fp_line
			(start -1.1049 -0.724916)
			(end 1.1049 -0.724916)
			(stroke
				(width 0.1)
				(type default)
			)
			(layer "B.Fab")
		)
		(fp_line
			(start 1.1049 -0.724916)
			(end 1.1049 0.724916)
			(stroke
				(width 0.1)
				(type default)
			)
			(layer "B.Fab")
		)
		(pad "1" smd rect
			(at 0.889 0 270)
			(size 1.016 1.27)
			(layers "B.Cu" "B.Mask" "B.Paste")
			(net "P1V8_CPU1_RT_1D")
		)
		(pad "2" smd rect
			(at -0.889 0 270)
			(size 1.016 1.27)
			(layers "B.Cu" "B.Mask" "B.Paste")
			(net "GND")
		)
	)
	(footprint ""
		(layer "B.Cu")
		(at 447.656966 -421.374824)
		(property "Reference" "PR6604"
			(at 0 0 0)
			(layer "B.SilkS")
			(hide yes)
			(effects
				(font
					(size 1.27 1.27)
				)
				(justify mirror)
			)
		)
		(property "Value" ""
			(at 0 0 0)
			(layer "B.Fab")
			(effects
				(font
					(size 1.27 1.27)
				)
				(justify mirror)
			)
		)
		(duplicate_pad_numbers_are_jumpers no)
		(fp_line
			(start -0.7874 -0.4064)
			(end -0.7874 0.4064)
			(stroke
				(width 0.1524)
				(type default)
			)
			(layer "B.SilkS")
		)
		(fp_line
			(start -0.7874 0.4064)
			(end 0.7874 0.4064)
			(stroke
				(width 0.1524)
				(type default)
			)
			(layer "B.SilkS")
		)
		(fp_line
			(start 0.7874 -0.4064)
			(end -0.7874 -0.4064)
			(stroke
				(width 0.1524)
				(type default)
			)
			(layer "B.SilkS")
		)
		(fp_line
			(start 0.7874 0.4064)
			(end 0.7874 -0.4064)
			(stroke
				(width 0.1524)
				(type default)
			)
			(layer "B.SilkS")
		)
		(fp_line
			(start -0.67945 -0.3048)
			(end -0.67945 0.3048)
			(stroke
				(width 0.1)
				(type default)
			)
			(layer "B.Fab")
		)
		(fp_line
			(start -0.67945 0.3048)
			(end -0.120396 0.3048)
			(stroke
				(width 0.1)
				(type default)
			)
			(layer "B.Fab")
		)
		(fp_line
			(start -0.12065 -0.3048)
			(end -0.67945 -0.3048)
			(stroke
				(width 0.1)
				(type default)
			)
			(layer "B.Fab")
		)
		(fp_line
			(start -0.12065 -0.2794)
			(end -0.12065 -0.3048)
			(stroke
				(width 0.1)
				(type default)
			)
			(layer "B.Fab")
		)
		(fp_line
			(start -0.120396 0.2794)
			(end 0.12065 0.2794)
			(stroke
				(width 0.1)
				(type default)
			)
			(layer "B.Fab")
		)
		(fp_line
			(start -0.120396 0.3048)
			(end -0.120396 0.2794)
			(stroke
				(width 0.1)
				(type default)
			)
			(layer "B.Fab")
		)
		(fp_line
			(start 0.12065 -0.305054)
			(end 0.12065 -0.2794)
			(stroke
				(width 0.1)
				(type default)
			)
			(layer "B.Fab")
		)
		(fp_line
			(start 0.12065 -0.2794)
			(end -0.12065 -0.2794)
			(stroke
				(width 0.1)
				(type default)
			)
			(layer "B.Fab")
		)
		(fp_line
			(start 0.12065 0.2794)
			(end 0.12065 0.3048)
			(stroke
				(width 0.1)
				(type default)
			)
			(layer "B.Fab")
		)
		(fp_line
			(start 0.12065 0.3048)
			(end 0.67945 0.3048)
			(stroke
				(width 0.1)
				(type default)
			)
			(layer "B.Fab")
		)
		(fp_line
			(start 0.67945 -0.305054)
			(end 0.12065 -0.305054)
			(stroke
				(width 0.1)
				(type default)
			)
			(layer "B.Fab")
		)
		(fp_line
			(start 0.67945 0.3048)
			(end 0.67945 -0.305054)
			(stroke
				(width 0.1)
				(type default)
			)
			(layer "B.Fab")
		)
		(pad "1" smd circle
			(at 0.40005 0 180)
			(size 0 0)
			(layers "B.Cu" "B.Mask" "B.Paste")
			(net "P5V_AUX")
		)
		(pad "2" smd circle
			(at -0.40005 0 180)
			(size 0 0)
			(layers "B.Cu" "B.Mask" "B.Paste")
			(net "P0V9_RETIMER_CPU0_VMON")
		)
	)
	(footprint ""
		(layer "B.Cu")
		(at 120.377966 -408.517344 90)
		(property "Reference" "C6727"
			(at 0 0 90)
			(layer "B.SilkS")
			(hide yes)
			(effects
				(font
					(size 1.27 1.27)
				)
				(justify mirror)
			)
		)
		(property "Value" ""
			(at 0 0 90)
			(layer "B.Fab")
			(effects
				(font
					(size 1.27 1.27)
				)
				(justify mirror)
			)
		)
		(duplicate_pad_numbers_are_jumpers no)
		(fp_line
			(start 0.299974 -0.150114)
			(end -0.299974 -0.150114)
			(stroke
				(width 0.1)
				(type default)
			)
			(layer "B.Fab")
		)
		(fp_line
			(start -0.299974 -0.150114)
			(end -0.299974 0.150114)
			(stroke
				(width 0.1)
				(type default)
			)
			(layer "B.Fab")
		)
		(fp_line
			(start 0.299974 0.150114)
			(end 0.299974 -0.150114)
			(stroke
				(width 0.1)
				(type default)
			)
			(layer "B.Fab")
		)
		(fp_line
			(start -0.299974 0.150114)
			(end 0.299974 0.150114)
			(stroke
				(width 0.1)
				(type default)
			)
			(layer "B.Fab")
		)
		(pad "1" smd rect
			(at 0.2667 0 270)
			(size 0.3048 0.381)
			(layers "B.Cu" "B.Mask" "B.Paste")
			(net "P5E_CPU1_P3_TX_BUF_C_DP<1>")
		)
		(pad "2" smd rect
			(at -0.2667 0 270)
			(size 0.3048 0.381)
			(layers "B.Cu" "B.Mask" "B.Paste")
			(net "P5E_CPU1_P3_TX_BUF_DP<1>")
		)
	)
	(footprint ""
		(layer "B.Cu")
		(at 190.367412 -13.60043 -90)
		(property "Reference" "R6000"
			(at 0 0 90)
			(layer "B.SilkS")
			(hide yes)
			(effects
				(font
					(size 1.27 1.27)
				)
				(justify mirror)
			)
		)
		(property "Value" ""
			(at 0 0 90)
			(layer "B.Fab")
			(effects
				(font
					(size 1.27 1.27)
				)
				(justify mirror)
			)
		)
		(duplicate_pad_numbers_are_jumpers no)
		(fp_line
			(start -0.7874 0.4064)
			(end 0.7874 0.4064)
			(stroke
				(width 0.1524)
				(type default)
			)
			(layer "B.SilkS")
		)
		(fp_line
			(start 0.7874 0.4064)
			(end 0.7874 -0.4064)
			(stroke
				(width 0.1524)
				(type default)
			)
			(layer "B.SilkS")
		)
		(fp_line
			(start -0.7874 -0.4064)
			(end -0.7874 0.4064)
			(stroke
				(width 0.1524)
				(type default)
			)
			(layer "B.SilkS")
		)
		(fp_line
			(start 0.7874 -0.4064)
			(end -0.7874 -0.4064)
			(stroke
				(width 0.1524)
				(type default)
			)
			(layer "B.SilkS")
		)
		(fp_line
			(start -0.67945 0.3048)
			(end -0.120396 0.3048)
			(stroke
				(width 0.1)
				(type default)
			)
			(layer "B.Fab")
		)
		(fp_line
			(start -0.120396 0.3048)
			(end -0.120396 0.2794)
			(stroke
				(width 0.1)
				(type default)
			)
			(layer "B.Fab")
		)
		(fp_line
			(start 0.12065 0.3048)
			(end 0.67945 0.3048)
			(stroke
				(width 0.1)
				(type default)
			)
			(layer "B.Fab")
		)
		(fp_line
			(start 0.67945 0.3048)
			(end 0.67945 -0.305054)
			(stroke
				(width 0.1)
				(type default)
			)
			(layer "B.Fab")
		)
		(fp_line
			(start -0.120396 0.2794)
			(end 0.12065 0.2794)
			(stroke
				(width 0.1)
				(type default)
			)
			(layer "B.Fab")
		)
		(fp_line
			(start 0.12065 0.2794)
			(end 0.12065 0.3048)
			(stroke
				(width 0.1)
				(type default)
			)
			(layer "B.Fab")
		)
		(fp_line
			(start -0.12065 -0.2794)
			(end -0.12065 -0.3048)
			(stroke
				(width 0.1)
				(type default)
			)
			(layer "B.Fab")
		)
		(fp_line
			(start 0.12065 -0.2794)
			(end -0.12065 -0.2794)
			(stroke
				(width 0.1)
				(type default)
			)
			(layer "B.Fab")
		)
		(fp_line
			(start -0.67945 -0.3048)
			(end -0.67945 0.3048)
			(stroke
				(width 0.1)
				(type default)
			)
			(layer "B.Fab")
		)
		(fp_line
			(start -0.12065 -0.3048)
			(end -0.67945 -0.3048)
			(stroke
				(width 0.1)
				(type default)
			)
			(layer "B.Fab")
		)
		(fp_line
			(start 0.12065 -0.305054)
			(end 0.12065 -0.2794)
			(stroke
				(width 0.1)
				(type default)
			)
			(layer "B.Fab")
		)
		(fp_line
			(start 0.67945 -0.305054)
			(end 0.12065 -0.305054)
			(stroke
				(width 0.1)
				(type default)
			)
			(layer "B.Fab")
		)
		(pad "1" smd circle
			(at 0.40005 0 90)
			(size 0 0)
			(layers "B.Cu" "B.Mask" "B.Paste")
			(net "I3C_SCM_0_SCL")
		)
		(pad "2" smd circle
			(at -0.40005 0 90)
			(size 0 0)
			(layers "B.Cu" "B.Mask" "B.Paste")
			(net "I3C_SCM_0_R_SCL")
		)
	)
	(footprint ""
		(layer "B.Cu")
		(at 49.778666 -386.766562 90)
		(property "Reference" "C138"
			(at 0 0 90)
			(layer "B.SilkS")
			(hide yes)
			(effects
				(font
					(size 1.27 1.27)
				)
				(justify mirror)
			)
		)
		(property "Value" ""
			(at 0 0 90)
			(layer "B.Fab")
			(effects
				(font
					(size 1.27 1.27)
				)
				(justify mirror)
			)
		)
		(duplicate_pad_numbers_are_jumpers no)
		(fp_line
			(start 0.299974 -0.150114)
			(end -0.299974 -0.150114)
			(stroke
				(width 0.1)
				(type default)
			)
			(layer "B.Fab")
		)
		(fp_line
			(start -0.299974 -0.150114)
			(end -0.299974 0.150114)
			(stroke
				(width 0.1)
				(type default)
			)
			(layer "B.Fab")
		)
		(fp_line
			(start 0.299974 0.150114)
			(end 0.299974 -0.150114)
			(stroke
				(width 0.1)
				(type default)
			)
			(layer "B.Fab")
		)
		(fp_line
			(start -0.299974 0.150114)
			(end 0.299974 0.150114)
			(stroke
				(width 0.1)
				(type default)
			)
			(layer "B.Fab")
		)
		(pad "1" smd rect
			(at 0.2667 0 270)
			(size 0.3048 0.381)
			(layers "B.Cu" "B.Mask" "B.Paste")
			(net "P0V9_CPU1_RT0_2A")
		)
		(pad "2" smd rect
			(at -0.2667 0 270)
			(size 0.3048 0.381)
			(layers "B.Cu" "B.Mask" "B.Paste")
			(net "GND")
		)
	)
	(footprint ""
		(layer "B.Cu")
		(at 82.446368 -388.011162 -90)
		(property "Reference" "C319"
			(at 0 0 90)
			(layer "B.SilkS")
			(hide yes)
			(effects
				(font
					(size 1.27 1.27)
				)
				(justify mirror)
			)
		)
		(property "Value" ""
			(at 0 0 90)
			(layer "B.Fab")
			(effects
				(font
					(size 1.27 1.27)
				)
				(justify mirror)
			)
		)
		(duplicate_pad_numbers_are_jumpers no)
		(fp_line
			(start -0.299974 0.150114)
			(end 0.299974 0.150114)
			(stroke
				(width 0.1)
				(type default)
			)
			(layer "B.Fab")
		)
		(fp_line
			(start 0.299974 0.150114)
			(end 0.299974 -0.150114)
			(stroke
				(width 0.1)
				(type default)
			)
			(layer "B.Fab")
		)
		(fp_line
			(start -0.299974 -0.150114)
			(end -0.299974 0.150114)
			(stroke
				(width 0.1)
				(type default)
			)
			(layer "B.Fab")
		)
		(fp_line
			(start 0.299974 -0.150114)
			(end -0.299974 -0.150114)
			(stroke
				(width 0.1)
				(type default)
			)
			(layer "B.Fab")
		)
		(pad "1" smd rect
			(at 0.2667 0 90)
			(size 0.3048 0.381)
			(layers "B.Cu" "B.Mask" "B.Paste")
			(net "P0V9_CPU1_RT1_2A")
		)
		(pad "2" smd rect
			(at -0.2667 0 90)
			(size 0.3048 0.381)
			(layers "B.Cu" "B.Mask" "B.Paste")
			(net "GND")
		)
	)
	(footprint ""
		(layer "B.Cu")
		(at 286.893 -415.798 -90)
		(property "Reference" "C80"
			(at 0 0 90)
			(layer "B.SilkS")
			(hide yes)
			(effects
				(font
					(size 1.27 1.27)
				)
				(justify mirror)
			)
		)
		(property "Value" ""
			(at 0 0 90)
			(layer "B.Fab")
			(effects
				(font
					(size 1.27 1.27)
				)
				(justify mirror)
			)
		)
		(duplicate_pad_numbers_are_jumpers no)
		(fp_line
			(start -0.7874 0.4064)
			(end 0.7874 0.4064)
			(stroke
				(width 0.1524)
				(type default)
			)
			(layer "B.SilkS")
		)
		(fp_line
			(start 0.7874 0.4064)
			(end 0.7874 -0.4064)
			(stroke
				(width 0.1524)
				(type default)
			)
			(layer "B.SilkS")
		)
		(fp_line
			(start -0.7874 -0.4064)
			(end -0.7874 0.4064)
			(stroke
				(width 0.1524)
				(type default)
			)
			(layer "B.SilkS")
		)
		(fp_line
			(start 0.7874 -0.4064)
			(end -0.7874 -0.4064)
			(stroke
				(width 0.1524)
				(type default)
			)
			(layer "B.SilkS")
		)
		(fp_line
			(start -0.67945 0.3048)
			(end -0.120396 0.3048)
			(stroke
				(width 0.1)
				(type default)
			)
			(layer "B.Fab")
		)
		(fp_line
			(start -0.120396 0.3048)
			(end -0.120396 0.2794)
			(stroke
				(width 0.1)
				(type default)
			)
			(layer "B.Fab")
		)
		(fp_line
			(start 0.12065 0.3048)
			(end 0.67945 0.3048)
			(stroke
				(width 0.1)
				(type default)
			)
			(layer "B.Fab")
		)
		(fp_line
			(start 0.67945 0.3048)
			(end 0.67945 -0.305054)
			(stroke
				(width 0.1)
				(type default)
			)
			(layer "B.Fab")
		)
		(fp_line
			(start -0.120396 0.2794)
			(end 0.12065 0.2794)
			(stroke
				(width 0.1)
				(type default)
			)
			(layer "B.Fab")
		)
		(fp_line
			(start 0.12065 0.2794)
			(end 0.12065 0.3048)
			(stroke
				(width 0.1)
				(type default)
			)
			(layer "B.Fab")
		)
		(fp_line
			(start -0.12065 -0.2794)
			(end -0.12065 -0.3048)
			(stroke
				(width 0.1)
				(type default)
			)
			(layer "B.Fab")
		)
		(fp_line
			(start 0.12065 -0.2794)
			(end -0.12065 -0.2794)
			(stroke
				(width 0.1)
				(type default)
			)
			(layer "B.Fab")
		)
		(fp_line
			(start -0.67945 -0.3048)
			(end -0.67945 0.3048)
			(stroke
				(width 0.1)
				(type default)
			)
			(layer "B.Fab")
		)
		(fp_line
			(start -0.12065 -0.3048)
			(end -0.67945 -0.3048)
			(stroke
				(width 0.1)
				(type default)
			)
			(layer "B.Fab")
		)
		(fp_line
			(start 0.12065 -0.305054)
			(end 0.12065 -0.2794)
			(stroke
				(width 0.1)
				(type default)
			)
			(layer "B.Fab")
		)
		(fp_line
			(start 0.67945 -0.305054)
			(end 0.12065 -0.305054)
			(stroke
				(width 0.1)
				(type default)
			)
			(layer "B.Fab")
		)
		(pad "1" smd circle
			(at 0.40005 0 90)
			(size 0 0)
			(layers "B.Cu" "B.Mask" "B.Paste")
			(net "P3V3_9ZXL045_P0_VDD")
		)
		(pad "2" smd circle
			(at -0.40005 0 90)
			(size 0 0)
			(layers "B.Cu" "B.Mask" "B.Paste")
			(net "GND")
		)
	)
	(footprint ""
		(layer "B.Cu")
		(at 17.779492 -97.342198 90)
		(property "Reference" "C2040"
			(at 0 0 90)
			(layer "B.SilkS")
			(hide yes)
			(effects
				(font
					(size 1.27 1.27)
				)
				(justify mirror)
			)
		)
		(property "Value" ""
			(at 0 0 90)
			(layer "B.Fab")
			(effects
				(font
					(size 1.27 1.27)
				)
				(justify mirror)
			)
		)
		(duplicate_pad_numbers_are_jumpers no)
		(fp_line
			(start 0.7874 -0.4064)
			(end -0.7874 -0.4064)
			(stroke
				(width 0.1524)
				(type default)
			)
			(layer "B.SilkS")
		)
		(fp_line
			(start -0.7874 -0.4064)
			(end -0.7874 0.4064)
			(stroke
				(width 0.1524)
				(type default)
			)
			(layer "B.SilkS")
		)
		(fp_line
			(start 0.7874 0.4064)
			(end 0.7874 -0.4064)
			(stroke
				(width 0.1524)
				(type default)
			)
			(layer "B.SilkS")
		)
		(fp_line
			(start -0.7874 0.4064)
			(end 0.7874 0.4064)
			(stroke
				(width 0.1524)
				(type default)
			)
			(layer "B.SilkS")
		)
		(fp_line
			(start 0.67945 -0.305054)
			(end 0.12065 -0.305054)
			(stroke
				(width 0.1)
				(type default)
			)
			(layer "B.Fab")
		)
		(fp_line
			(start 0.12065 -0.305054)
			(end 0.12065 -0.2794)
			(stroke
				(width 0.1)
				(type default)
			)
			(layer "B.Fab")
		)
		(fp_line
			(start -0.12065 -0.3048)
			(end -0.67945 -0.3048)
			(stroke
				(width 0.1)
				(type default)
			)
			(layer "B.Fab")
		)
		(fp_line
			(start -0.67945 -0.3048)
			(end -0.67945 0.3048)
			(stroke
				(width 0.1)
				(type default)
			)
			(layer "B.Fab")
		)
		(fp_line
			(start 0.12065 -0.2794)
			(end -0.12065 -0.2794)
			(stroke
				(width 0.1)
				(type default)
			)
			(layer "B.Fab")
		)
		(fp_line
			(start -0.12065 -0.2794)
			(end -0.12065 -0.3048)
			(stroke
				(width 0.1)
				(type default)
			)
			(layer "B.Fab")
		)
		(fp_line
			(start 0.12065 0.2794)
			(end 0.12065 0.3048)
			(stroke
				(width 0.1)
				(type default)
			)
			(layer "B.Fab")
		)
		(fp_line
			(start -0.120396 0.2794)
			(end 0.12065 0.2794)
			(stroke
				(width 0.1)
				(type default)
			)
			(layer "B.Fab")
		)
		(fp_line
			(start 0.67945 0.3048)
			(end 0.67945 -0.305054)
			(stroke
				(width 0.1)
				(type default)
			)
			(layer "B.Fab")
		)
		(fp_line
			(start 0.12065 0.3048)
			(end 0.67945 0.3048)
			(stroke
				(width 0.1)
				(type default)
			)
			(layer "B.Fab")
		)
		(fp_line
			(start -0.120396 0.3048)
			(end -0.120396 0.2794)
			(stroke
				(width 0.1)
				(type default)
			)
			(layer "B.Fab")
		)
		(fp_line
			(start -0.67945 0.3048)
			(end -0.120396 0.3048)
			(stroke
				(width 0.1)
				(type default)
			)
			(layer "B.Fab")
		)
		(pad "1" smd circle
			(at 0.40005 0 270)
			(size 0 0)
			(layers "B.Cu" "B.Mask" "B.Paste")
			(net "P3V3_AUX_USB_HUB")
		)
		(pad "2" smd circle
			(at -0.40005 0 270)
			(size 0 0)
			(layers "B.Cu" "B.Mask" "B.Paste")
			(net "GND")
		)
	)
	(footprint ""
		(layer "B.Cu")
		(at 331.793342 -392.1252 180)
		(property "Reference" "R1022"
			(at 0 0 0)
			(layer "B.SilkS")
			(hide yes)
			(effects
				(font
					(size 1.27 1.27)
				)
				(justify mirror)
			)
		)
		(property "Value" ""
			(at 0 0 0)
			(layer "B.Fab")
			(effects
				(font
					(size 1.27 1.27)
				)
				(justify mirror)
			)
		)
		(duplicate_pad_numbers_are_jumpers no)
		(fp_line
			(start 0.32512 0.175006)
			(end 0.32512 -0.175006)
			(stroke
				(width 0.1)
				(type default)
			)
			(layer "B.Fab")
		)
		(fp_line
			(start 0.32512 -0.175006)
			(end -0.32512 -0.175006)
			(stroke
				(width 0.1)
				(type default)
			)
			(layer "B.Fab")
		)
		(fp_line
			(start -0.32512 0.175006)
			(end 0.32512 0.175006)
			(stroke
				(width 0.1)
				(type default)
			)
			(layer "B.Fab")
		)
		(fp_line
			(start -0.32512 -0.175006)
			(end -0.32512 0.175006)
			(stroke
				(width 0.1)
				(type default)
			)
			(layer "B.Fab")
		)
		(pad "1" smd rect
			(at 0.2667 0)
			(size 0.3048 0.381)
			(layers "B.Cu" "B.Mask" "B.Paste")
			(net "RT_CPU0_P1_SCAN_MODE")
		)
		(pad "2" smd rect
			(at -0.2667 0 180)
			(size 0.3048 0.381)
			(layers "B.Cu" "B.Mask" "B.Paste")
			(net "GND")
		)
	)
)
